# T6G (Grand Teton) — schematic netlist excerpt (pin names and nets, part order shuffled) for the footprints in the layout excerpt that follows; sources: Cadence DE-HDL packaged netlist, KiCad conversion of 04192023_DAF0TMB3IC0_F0TG_MB_C_brd_V02_OCP.brd

R5099  Q_RES  0 5% CHIP  pkg 0402LF  page 81 : A = FPGA_DEBUG_SW_SPARE ; B = FM_FPGA_DEBUG_SW_SPARE
PR417  Q_RES  0 5% CHIP  pkg 0402LF  page 209 : A = GND ; B = PVDD18_S5_P0_MODE

(kicad_pcb
	(version 20260206)
	(generator "pcbnew")
	(generator_version "10.0")
	(general
		(thickness 1.6)
		(legacy_teardrops no)
	)
	(paper "A4")
	(title_block
		(title "04192023_DAF0TMB3IC0_F0TG_MB_C_brd_V02_OCP.brd")
		(comment 1 "Grand Teton / footprints 3332-3333 of 8354")
	)
	(layers
		(0 "F.Cu" signal "TOP")
		(4 "In1.Cu" signal "GND")
		(6 "In2.Cu" signal "IN1")
		(8 "In3.Cu" signal "GND1")
		(10 "In4.Cu" signal "IN2")
		(12 "In5.Cu" signal "GND2")
		(14 "In6.Cu" signal "IN3")
		(16 "In7.Cu" signal "GND3")
		(18 "In8.Cu" signal "VCC")
		(20 "In9.Cu" signal "VCC1")
		(22 "In10.Cu" signal "GND4")
		(24 "In11.Cu" signal "IN4")
		(26 "In12.Cu" signal "GND5")
		(28 "In13.Cu" signal "IN5")
		(30 "In14.Cu" signal "GND6")
		(32 "In15.Cu" signal "IN6")
		(34 "In16.Cu" signal "GND7")
		(2 "B.Cu" signal "BOTTOM")
		(9 "F.Adhes" user "F.Adhesive")
		(11 "B.Adhes" user "B.Adhesive")
		(13 "F.Paste" user "Package Geometry/Pastemask Top")
		(15 "B.Paste" user "Package Geometry/Pastemask Bottom")
		(5 "F.SilkS" user "Ref Des/Silkscreen Top")
		(7 "B.SilkS" user "Ref Des/Silkscreen Bottom")
		(1 "F.Mask" user "Board Geometry/Soldermask Top")
		(3 "B.Mask" user "Board Geometry/Soldermask Bottom")
		(17 "Dwgs.User" user "User.Drawings")
		(19 "Cmts.User" user "User.Comments")
		(21 "Eco1.User" user "User.Eco1")
		(23 "Eco2.User" user "User.Eco2")
		(25 "Edge.Cuts" user "Board Geometry/Outline")
		(27 "Margin" user)
		(31 "F.CrtYd" user "Package Geometry/Place Bound Top")
		(29 "B.CrtYd" user "Package Geometry/Place Bound Bottom")
		(35 "F.Fab" user "Ref Des/Assembly Top")
		(33 "B.Fab" user "Ref Des/Assembly Bottom")
	)
	(footprint ""
		(layer "F.Cu")
		(at 208.894426 -112.662208 180)
		(property "Reference" "R5099"
			(at 0 0 180)
			(layer "F.SilkS")
			(hide yes)
			(effects
				(font
					(size 1.27 1.27)
				)
			)
		)
		(property "Value" ""
			(at 0 0 180)
			(layer "F.Fab")
			(effects
				(font
					(size 1.27 1.27)
				)
			)
		)
		(duplicate_pad_numbers_are_jumpers no)
		(fp_line
			(start 0.7874 0.4064)
			(end -0.7874 0.4064)
			(stroke
				(width 0.1524)
				(type default)
			)
			(layer "F.SilkS")
		)
		(fp_line
			(start 0.7874 -0.4064)
			(end 0.7874 0.4064)
			(stroke
				(width 0.1524)
				(type default)
			)
			(layer "F.SilkS")
		)
		(fp_line
			(start -0.7874 0.4064)
			(end -0.7874 -0.4064)
			(stroke
				(width 0.1524)
				(type default)
			)
			(layer "F.SilkS")
		)
		(fp_line
			(start -0.7874 -0.4064)
			(end 0.7874 -0.4064)
			(stroke
				(width 0.1524)
				(type default)
			)
			(layer "F.SilkS")
		)
		(fp_line
			(start 0.67945 0.3048)
			(end 0.120396 0.3048)
			(stroke
				(width 0.1)
				(type default)
			)
			(layer "F.Fab")
		)
		(fp_line
			(start 0.67945 -0.3048)
			(end 0.67945 0.3048)
			(stroke
				(width 0.1)
				(type default)
			)
			(layer "F.Fab")
		)
		(fp_line
			(start 0.12065 -0.2794)
			(end 0.12065 -0.3048)
			(stroke
				(width 0.1)
				(type default)
			)
			(layer "F.Fab")
		)
		(fp_line
			(start 0.12065 -0.3048)
			(end 0.67945 -0.3048)
			(stroke
				(width 0.1)
				(type default)
			)
			(layer "F.Fab")
		)
		(fp_line
			(start 0.120396 0.3048)
			(end 0.120396 0.2794)
			(stroke
				(width 0.1)
				(type default)
			)
			(layer "F.Fab")
		)
		(fp_line
			(start 0.120396 0.2794)
			(end -0.12065 0.2794)
			(stroke
				(width 0.1)
				(type default)
			)
			(layer "F.Fab")
		)
		(fp_line
			(start -0.12065 0.3048)
			(end -0.67945 0.3048)
			(stroke
				(width 0.1)
				(type default)
			)
			(layer "F.Fab")
		)
		(fp_line
			(start -0.12065 0.2794)
			(end -0.12065 0.3048)
			(stroke
				(width 0.1)
				(type default)
			)
			(layer "F.Fab")
		)
		(fp_line
			(start -0.12065 -0.2794)
			(end 0.12065 -0.2794)
			(stroke
				(width 0.1)
				(type default)
			)
			(layer "F.Fab")
		)
		(fp_line
			(start -0.12065 -0.305054)
			(end -0.12065 -0.2794)
			(stroke
				(width 0.1)
				(type default)
			)
			(layer "F.Fab")
		)
		(fp_line
			(start -0.67945 0.3048)
			(end -0.67945 -0.305054)
			(stroke
				(width 0.1)
				(type default)
			)
			(layer "F.Fab")
		)
		(fp_line
			(start -0.67945 -0.305054)
			(end -0.12065 -0.305054)
			(stroke
				(width 0.1)
				(type default)
			)
			(layer "F.Fab")
		)
		(pad "1" smd circle
			(at -0.40005 0 180)
			(size 0 0)
			(layers "F.Cu" "F.Mask" "F.Paste")
			(net "FPGA_DEBUG_SW_SPARE")
		)
		(pad "2" smd circle
			(at 0.40005 0 180)
			(size 0 0)
			(layers "F.Cu" "F.Mask" "F.Paste")
			(net "FM_FPGA_DEBUG_SW_SPARE")
		)
	)
	(footprint ""
		(layer "F.Cu")
		(at 331.662532 -141.36243)
		(property "Reference" "PR417"
			(at 0 0 0)
			(layer "F.SilkS")
			(hide yes)
			(effects
				(font
					(size 1.27 1.27)
				)
			)
		)
		(property "Value" ""
			(at 0 0 0)
			(layer "F.Fab")
			(effects
				(font
					(size 1.27 1.27)
				)
			)
		)
		(duplicate_pad_numbers_are_jumpers no)
		(fp_line
			(start -0.7874 -0.4064)
			(end 0.7874 -0.4064)
			(stroke
				(width 0.1524)
				(type default)
			)
			(layer "F.SilkS")
		)
		(fp_line
			(start -0.7874 0.4064)
			(end -0.7874 -0.4064)
			(stroke
				(width 0.1524)
				(type default)
			)
			(layer "F.SilkS")
		)
		(fp_line
			(start 0.7874 -0.4064)
			(end 0.7874 0.4064)
			(stroke
				(width 0.1524)
				(type default)
			)
			(layer "F.SilkS")
		)
		(fp_line
			(start 0.7874 0.4064)
			(end -0.7874 0.4064)
			(stroke
				(width 0.1524)
				(type default)
			)
			(layer "F.SilkS")
		)
		(fp_line
			(start -0.67945 -0.305054)
			(end -0.12065 -0.305054)
			(stroke
				(width 0.1)
				(type default)
			)
			(layer "F.Fab")
		)
		(fp_line
			(start -0.67945 0.3048)
			(end -0.67945 -0.305054)
			(stroke
				(width 0.1)
				(type default)
			)
			(layer "F.Fab")
		)
		(fp_line
			(start -0.12065 -0.305054)
			(end -0.12065 -0.2794)
			(stroke
				(width 0.1)
				(type default)
			)
			(layer "F.Fab")
		)
		(fp_line
			(start -0.12065 -0.2794)
			(end 0.12065 -0.2794)
			(stroke
				(width 0.1)
				(type default)
			)
			(layer "F.Fab")
		)
		(fp_line
			(start -0.12065 0.2794)
			(end -0.12065 0.3048)
			(stroke
				(width 0.1)
				(type default)
			)
			(layer "F.Fab")
		)
		(fp_line
			(start -0.12065 0.3048)
			(end -0.67945 0.3048)
			(stroke
				(width 0.1)
				(type default)
			)
			(layer "F.Fab")
		)
		(fp_line
			(start 0.120396 0.2794)
			(end -0.12065 0.2794)
			(stroke
				(width 0.1)
				(type default)
			)
			(layer "F.Fab")
		)
		(fp_line
			(start 0.120396 0.3048)
			(end 0.120396 0.2794)
			(stroke
				(width 0.1)
				(type default)
			)
			(layer "F.Fab")
		)
		(fp_line
			(start 0.12065 -0.3048)
			(end 0.67945 -0.3048)
			(stroke
				(width 0.1)
				(type default)
			)
			(layer "F.Fab")
		)
		(fp_line
			(start 0.12065 -0.2794)
			(end 0.12065 -0.3048)
			(stroke
				(width 0.1)
				(type default)
			)
			(layer "F.Fab")
		)
		(fp_line
			(start 0.67945 -0.3048)
			(end 0.67945 0.3048)
			(stroke
				(width 0.1)
				(type default)
			)
			(layer "F.Fab")
		)
		(fp_line
			(start 0.67945 0.3048)
			(end 0.120396 0.3048)
			(stroke
				(width 0.1)
				(type default)
			)
			(layer "F.Fab")
		)
		(pad "1" smd circle
			(at -0.40005 0)
			(size 0 0)
			(layers "F.Cu" "F.Mask" "F.Paste")
			(net "GND")
		)
		(pad "2" smd circle
			(at 0.40005 0)
			(size 0 0)
			(layers "F.Cu" "F.Mask" "F.Paste")
			(net "PVDD18_S5_P0_MODE")
		)
	)
)
